(kicad_pcb
	(version 20241229)
	(generator "pcbnew")
	(generator_version "9.0")
	(general
		(thickness 1.62)
		(legacy_teardrops no)
	)
	(paper "A3")
	(title_block
		(title "COM Express 7 Baseboard")
		(date "2025-02-04")
		(rev "1.1.2")
		(company "Antmicro Ltd")
		(comment 1 "www.antmicro.com")
		(comment 9 "footprints 33-38 of 802")
	)
	(layers
		(0 "F.Cu" signal)
		(4 "In1.Cu" signal)
		(6 "In2.Cu" signal)
		(8 "In3.Cu" signal)
		(10 "In4.Cu" signal)
		(12 "In5.Cu" signal)
		(14 "In6.Cu" signal)
		(2 "B.Cu" signal)
		(9 "F.Adhes" user "F.Adhesive")
		(11 "B.Adhes" user "B.Adhesive")
		(13 "F.Paste" user)
		(15 "B.Paste" user)
		(5 "F.SilkS" user "F.Silkscreen")
		(7 "B.SilkS" user "B.Silkscreen")
		(1 "F.Mask" user)
		(3 "B.Mask" user)
		(17 "Dwgs.User" user "User.Drawings")
		(19 "Cmts.User" user "User.Comments")
		(21 "Eco1.User" user "User.Eco1")
		(23 "Eco2.User" user "User.Eco2")
		(25 "Edge.Cuts" user)
		(27 "Margin" user)
		(31 "F.CrtYd" user "F.Courtyard")
		(29 "B.CrtYd" user "B.Courtyard")
		(35 "F.Fab" user)
		(33 "B.Fab" user)
	)
	(footprint "antmicro-footprints:R_0201"
		(layer "F.Cu")
		(at 146.57 147.31 -90)
		(descr "Resistor SMD 0201")
		(tags "resistor SMD 0201")
		(property "Reference" "R274"
			(at 4.125 -0.28 270)
			(layer "F.SilkS")
			(effects
				(font
					(size 0.7 0.7)
					(thickness 0.15)
				)
				(justify left bottom)
			)
		)
		(property "Value" "R_0R_0201"
			(at 0 1.25 270)
			(layer "F.Fab")
			(effects
				(font
					(size 0.7 0.7)
					(thickness 0.15)
				)
				(justify left bottom)
			)
		)
		(property "Datasheet" "https://www.bourns.com/docs/product-datasheets/cr.pdf"
			(at 0 0 270)
			(layer "F.Fab")
			(hide yes)
			(effects
				(font
					(size 1.27 1.27)
					(thickness 0.15)
				)
			)
		)
		(property "Author" "Antmicro"
			(at -0.74 293.88 0)
			(layer "F.Fab")
			(hide yes)
			(effects
				(font
					(size 1 1)
					(thickness 0.15)
				)
			)
		)
		(property "License" "Apache-2.0"
			(at -0.74 293.88 0)
			(layer "F.Fab")
			(hide yes)
			(effects
				(font
					(size 1 1)
					(thickness 0.15)
				)
			)
		)
		(property "MPN" "CR0201-FX-0R00GLF"
			(at -0.74 293.88 0)
			(layer "F.Fab")
			(hide yes)
			(effects
				(font
					(size 1 1)
					(thickness 0.15)
				)
			)
		)
		(property "Manufacturer" "Bourns"
			(at -0.74 293.88 0)
			(layer "F.Fab")
			(hide yes)
			(effects
				(font
					(size 1 1)
					(thickness 0.15)
				)
			)
		)
		(property "Tolerance" "1%"
			(at -0.74 293.88 0)
			(layer "F.Fab")
			(hide yes)
			(effects
				(font
					(size 1 1)
					(thickness 0.15)
				)
			)
		)
		(property "Val" "0R"
			(at -0.74 293.88 0)
			(layer "F.Fab")
			(hide yes)
			(effects
				(font
					(size 1 1)
					(thickness 0.15)
				)
			)
		)
		(sheetname "KR to SFI #1")
		(sheetfile "kr_sfi.kicad_sch")
		(attr smd)
		(fp_rect
			(start -0.7 -0.35)
			(end 0.7 0.35)
			(stroke
				(width 0.05)
				(type default)
			)
			(fill no)
			(layer "F.CrtYd")
		)
		(fp_rect
			(start -0.3 -0.15)
			(end 0.298 0.148)
			(stroke
				(width 0.15)
				(type solid)
			)
			(fill no)
			(layer "F.Fab")
		)
		(pad "" smd roundrect
			(at -0.346 0 270)
			(size 0.318 0.36)
			(layers "F.Paste")
			(roundrect_rratio 0.25)
			(teardrops
				(best_length_ratio 0.2)
				(max_length 1)
				(best_width_ratio 0.9)
				(max_width 2)
				(curved_edges yes)
				(filter_ratio 0.9)
				(enabled yes)
				(allow_two_segments yes)
				(prefer_zone_connections yes)
			)
		)
		(pad "" smd roundrect
			(at 0.344 0 270)
			(size 0.318 0.36)
			(layers "F.Paste")
			(roundrect_rratio 0.25)
			(teardrops
				(best_length_ratio 0.2)
				(max_length 1)
				(best_width_ratio 0.9)
				(max_width 2)
				(curved_edges yes)
				(filter_ratio 0.9)
				(enabled yes)
				(allow_two_segments yes)
				(prefer_zone_connections yes)
			)
		)
		(pad "1" smd roundrect
			(at -0.32 0 270)
			(size 0.46 0.4)
			(layers "F.Cu" "F.Mask")
			(roundrect_rratio 0.25)
			(net 685 "/2xSFP+/KR to SFI #1/SFI_R.TX-")
			(pintype "passive")
			(teardrops
				(best_length_ratio 0.2)
				(max_length 1)
				(best_width_ratio 0.9)
				(max_width 2)
				(curved_edges yes)
				(filter_ratio 0.9)
				(enabled yes)
				(allow_two_segments yes)
				(prefer_zone_connections yes)
			)
		)
		(pad "2" smd roundrect
			(at 0.32 0 270)
			(size 0.46 0.4)
			(layers "F.Cu" "F.Mask")
			(roundrect_rratio 0.25)
			(net 173 "/2xSFP+/SFI0.TX-")
			(pintype "passive")
			(teardrops
				(best_length_ratio 0.2)
				(max_length 1)
				(best_width_ratio 0.9)
				(max_width 2)
				(curved_edges yes)
				(filter_ratio 0.9)
				(enabled yes)
				(allow_two_segments yes)
				(prefer_zone_connections yes)
			)
		)
	)
	(footprint "antmicro-footprints:TP_SMD_0.75mm"
		(layer "F.Cu")
		(at 150.5 128.71)
		(property "Reference" "TP73"
			(at 0.4 -3.3 90)
			(layer "F.SilkS")
			(effects
				(font
					(size 0.7 0.7)
					(thickness 0.15)
				)
				(justify left bottom)
			)
		)
		(property "Value" "TP_0.75mm_SMD"
			(at 0 1.2 0)
			(layer "F.Fab")
			(effects
				(font
					(size 0.7 0.7)
					(thickness 0.15)
				)
				(justify left bottom)
			)
		)
		(property "Author" "Antmicro"
			(at 0 0 0)
			(layer "F.Fab")
			(hide yes)
			(effects
				(font
					(size 1 1)
					(thickness 0.15)
				)
			)
		)
		(property "License" "Apache-2.0"
			(at 0 0 0)
			(layer "F.Fab")
			(hide yes)
			(effects
				(font
					(size 1 1)
					(thickness 0.15)
				)
			)
		)
		(property "MPN" ""
			(at 0 0 0)
			(layer "F.Fab")
			(hide yes)
			(effects
				(font
					(size 1 1)
					(thickness 0.15)
				)
			)
		)
		(property "Manufacturer" ""
			(at 0 0 0)
			(layer "F.Fab")
			(hide yes)
			(effects
				(font
					(size 1 1)
					(thickness 0.15)
				)
			)
		)
		(property "Public" "False"
			(at 0 0 0)
			(layer "F.Fab")
			(hide yes)
			(effects
				(font
					(size 1 1)
					(thickness 0.15)
				)
			)
		)
		(sheetname "KR to SFI #1")
		(sheetfile "kr_sfi.kicad_sch")
		(attr exclude_from_pos_files exclude_from_bom)
		(fp_circle
			(center 0 0)
			(end 0.475 0)
			(stroke
				(width 0.05)
				(type default)
			)
			(fill no)
			(layer "F.CrtYd")
		)
		(pad "1" smd circle
			(at 0 0)
			(size 0.75 0.75)
			(layers "F.Cu" "F.Mask")
			(net 736 "Net-(U43A-LS_OK_{OUT_A})")
			(pinfunction "1")
			(pintype "passive")
			(teardrops
				(best_length_ratio 0.4)
				(max_length 1)
				(best_width_ratio 0.9)
				(max_width 2)
				(curved_edges yes)
				(filter_ratio 0.9)
				(enabled yes)
				(allow_two_segments yes)
				(prefer_zone_connections yes)
			)
		)
	)
	(footprint "antmicro-footprints:C_0402_1005Metric"
		(layer "F.Cu")
		(at 192.841616 135.194859 135)
		(descr "Capacitor SMD 0402")
		(tags "capacitor SMD 0402")
		(property "Reference" "C134"
			(at 3.844168 0.249781 135)
			(layer "F.SilkS")
			(effects
				(font
					(size 0.7 0.7)
					(thickness 0.15)
				)
				(justify left top)
			)
		)
		(property "Value" "C_100n_0402"
			(at -1.022927 2.155213 135)
			(layer "F.Fab")
			(effects
				(font
					(size 0.7 0.7)
					(thickness 0.15)
				)
				(justify left top)
			)
		)
		(property "Datasheet" "https://www.murata.com/products/productdetail?partno=GRM155R61H104KE14%23"
			(at 0 0 135)
			(layer "B.Fab")
			(hide yes)
			(effects
				(font
					(size 1.27 1.27)
					(thickness 0.15)
				)
				(justify mirror)
			)
		)
		(property "Author" "Antmicro"
			(at 323.514 54.788 45)
			(layer "F.Fab")
			(hide yes)
			(effects
				(font
					(size 1 1)
					(thickness 0.15)
				)
			)
		)
		(property "Dielectric" "X5R"
			(at 323.514 54.788 45)
			(layer "F.Fab")
			(hide yes)
			(effects
				(font
					(size 1 1)
					(thickness 0.15)
				)
			)
		)
		(property "License" "Apache-2.0"
			(at 323.514 54.788 45)
			(layer "F.Fab")
			(hide yes)
			(effects
				(font
					(size 1 1)
					(thickness 0.15)
				)
			)
		)
		(property "MPN" "GRM155R61H104KE14D"
			(at 323.514 54.788 45)
			(layer "F.Fab")
			(hide yes)
			(effects
				(font
					(size 1 1)
					(thickness 0.15)
				)
			)
		)
		(property "Manufacturer" "Murata"
			(at 323.514 54.788 45)
			(layer "F.Fab")
			(hide yes)
			(effects
				(font
					(size 1 1)
					(thickness 0.15)
				)
			)
		)
		(property "Public" "False"
			(at 323.514 54.788 45)
			(layer "F.Fab")
			(hide yes)
			(effects
				(font
					(size 1 1)
					(thickness 0.15)
				)
			)
		)
		(property "Val" "100n"
			(at 323.514 54.788 45)
			(layer "F.Fab")
			(hide yes)
			(effects
				(font
					(size 1 1)
					(thickness 0.15)
				)
			)
		)
		(property "Voltage" "50V"
			(at 323.514 54.788 45)
			(layer "F.Fab")
			(hide yes)
			(effects
				(font
					(size 1 1)
					(thickness 0.15)
				)
			)
		)
		(sheetname "PCIe redriver")
		(sheetfile "pcie_redriver.kicad_sch")
		(attr smd)
		(fp_poly
			(pts
				(xy -0.925 -0.47) (xy 0.925 -0.47) (xy 0.925 0.47) (xy -0.925 0.47)
			)
			(stroke
				(width 0.05)
				(type default)
			)
			(fill no)
			(layer "F.CrtYd")
		)
		(fp_line
			(start 0.504 -0.25)
			(end 0.504 0.248)
			(stroke
				(width 0.15)
				(type solid)
			)
			(layer "F.Fab")
		)
		(fp_line
			(start 0.504 0.248)
			(end -0.494 0.248)
			(stroke
				(width 0.15)
				(type solid)
			)
			(layer "F.Fab")
		)
		(fp_line
			(start -0.494 -0.25)
			(end 0.504 -0.25)
			(stroke
				(width 0.15)
				(type solid)
			)
			(layer "F.Fab")
		)
		(fp_line
			(start -0.494 0.248)
			(end -0.494 -0.25)
			(stroke
				(width 0.15)
				(type solid)
			)
			(layer "F.Fab")
		)
		(pad "1" smd roundrect
			(at -0.48 0 135)
			(size 0.59 0.64)
			(layers "F.Cu" "F.Mask" "F.Paste")
			(roundrect_rratio 0.25)
			(net 1 "GND")
			(pintype "passive")
			(teardrops
				(best_length_ratio 0.2)
				(max_length 1)
				(best_width_ratio 0.9)
				(max_width 2)
				(curved_edges yes)
				(filter_ratio 0.9)
				(enabled yes)
				(allow_two_segments yes)
				(prefer_zone_connections yes)
			)
		)
		(pad "2" smd roundrect
			(at 0.48 0 135)
			(size 0.59 0.64)
			(layers "F.Cu" "F.Mask" "F.Paste")
			(roundrect_rratio 0.25)
			(net 2 "+3V3")
			(pintype "passive")
			(teardrops
				(best_length_ratio 0.2)
				(max_length 1)
				(best_width_ratio 0.9)
				(max_width 2)
				(curved_edges yes)
				(filter_ratio 0.9)
				(enabled yes)
				(allow_two_segments yes)
				(prefer_zone_connections yes)
			)
		)
	)
	(footprint "antmicro-footprints:R_0402_1005Metric"
		(layer "F.Cu")
		(at 136.6 109.22 180)
		(descr "Resistor SMD 0402")
		(tags "resistor SMD 0402")
		(property "Reference" "R16"
			(at -1.1 -1.4 0)
			(layer "F.SilkS")
			(effects
				(font
					(size 0.7 0.7)
					(thickness 0.15)
				)
				(justify right bottom)
			)
		)
		(property "Value" "R_75R_0402"
			(at -1.011843 1.772047 0)
			(layer "F.Fab")
			(effects
				(font
					(size 0.7 0.7)
					(thickness 0.15)
				)
				(justify right bottom)
			)
		)
		(property "Datasheet" "https://www.bourns.com/docs/product-datasheets/cr.pdf"
			(at 0 0 180)
			(layer "F.Fab")
			(hide yes)
			(effects
				(font
					(size 1.27 1.27)
					(thickness 0.15)
				)
			)
		)
		(property "Author" "Antmicro"
			(at 273.2 218.44 0)
			(layer "F.Fab")
			(hide yes)
			(effects
				(font
					(size 1 1)
					(thickness 0.15)
				)
			)
		)
		(property "License" "Apache-2.0"
			(at 273.2 218.44 0)
			(layer "F.Fab")
			(hide yes)
			(effects
				(font
					(size 1 1)
					(thickness 0.15)
				)
			)
		)
		(property "MPN" "CR0402-FX-75R0GLF"
			(at 273.2 218.44 0)
			(layer "F.Fab")
			(hide yes)
			(effects
				(font
					(size 1 1)
					(thickness 0.15)
				)
			)
		)
		(property "Manufacturer" "Bourns"
			(at 273.2 218.44 0)
			(layer "F.Fab")
			(hide yes)
			(effects
				(font
					(size 1 1)
					(thickness 0.15)
				)
			)
		)
		(property "Public" "False"
			(at 273.2 218.44 0)
			(layer "F.Fab")
			(hide yes)
			(effects
				(font
					(size 1 1)
					(thickness 0.15)
				)
			)
		)
		(property "Tolerance" "1%"
			(at 273.2 218.44 0)
			(layer "F.Fab")
			(hide yes)
			(effects
				(font
					(size 1 1)
					(thickness 0.15)
				)
			)
		)
		(property "Val" "75R"
			(at 273.2 218.44 0)
			(layer "F.Fab")
			(hide yes)
			(effects
				(font
					(size 1 1)
					(thickness 0.15)
				)
			)
		)
		(sheetname "2xUSB3.0+RJ45")
		(sheetfile "usb3+rj45.kicad_sch")
		(attr smd)
		(fp_rect
			(start -0.925 -0.47)
			(end 0.925 0.47)
			(stroke
				(width 0.05)
				(type default)
			)
			(fill no)
			(layer "F.CrtYd")
		)
		(fp_rect
			(start -0.5 -0.25)
			(end 0.5 0.25)
			(stroke
				(width 0.15)
				(type solid)
			)
			(fill no)
			(layer "F.Fab")
		)
		(pad "1" smd roundrect
			(at -0.48 0 180)
			(size 0.59 0.64)
			(layers "F.Cu" "F.Mask" "F.Paste")
			(roundrect_rratio 0.25)
			(net 50 "Net-(C12-Pad2)")
			(pintype "passive")
			(teardrops
				(best_length_ratio 0.2)
				(max_length 1)
				(best_width_ratio 0.9)
				(max_width 2)
				(curved_edges yes)
				(filter_ratio 0.9)
				(enabled yes)
				(allow_two_segments yes)
				(prefer_zone_connections yes)
			)
		)
		(pad "2" smd roundrect
			(at 0.48 0 180)
			(size 0.59 0.64)
			(layers "F.Cu" "F.Mask" "F.Paste")
			(roundrect_rratio 0.25)
			(net 551 "Net-(R16-Pad2)")
			(pintype "passive")
			(teardrops
				(best_length_ratio 0.2)
				(max_length 1)
				(best_width_ratio 0.9)
				(max_width 2)
				(curved_edges yes)
				(filter_ratio 0.9)
				(enabled yes)
				(allow_two_segments yes)
				(prefer_zone_connections yes)
			)
		)
	)
	(footprint "antmicro-footprints:C_0402_1005Metric"
		(layer "F.Cu")
		(at 291.75 101.86)
		(descr "Capacitor SMD 0402")
		(tags "capacitor SMD 0402")
		(property "Reference" "C70"
			(at 0.8 0.45 0)
			(layer "F.SilkS")
			(effects
				(font
					(size 0.7 0.7)
					(thickness 0.15)
				)
				(justify left bottom)
			)
		)
		(property "Value" "C_1u_0402"
			(at -1.022927 2.155213 0)
			(layer "F.Fab")
			(effects
				(font
					(size 0.7 0.7)
					(thickness 0.15)
				)
				(justify left bottom)
			)
		)
		(property "Datasheet" "https://product.tdk.com/en/search/capacitor/ceramic/mlcc/info?part_no=C1005X6S1A105K050BC"
			(at 0 0 0)
			(layer "F.Fab")
			(hide yes)
			(effects
				(font
					(size 1.27 1.27)
					(thickness 0.15)
				)
			)
		)
		(property "Author" "Antmicro"
			(at 0 0 0)
			(layer "F.Fab")
			(hide yes)
			(effects
				(font
					(size 1 1)
					(thickness 0.15)
				)
			)
		)
		(property "Dielectric" ""
			(at 0 0 0)
			(layer "F.Fab")
			(hide yes)
			(effects
				(font
					(size 1 1)
					(thickness 0.15)
				)
			)
		)
		(property "License" "Apache-2.0"
			(at 0 0 0)
			(layer "F.Fab")
			(hide yes)
			(effects
				(font
					(size 1 1)
					(thickness 0.15)
				)
			)
		)
		(property "MPN" "C1005X6S1A105K050BC"
			(at 0 0 0)
			(layer "F.Fab")
			(hide yes)
			(effects
				(font
					(size 1 1)
					(thickness 0.15)
				)
			)
		)
		(property "Manufacturer" "TDK"
			(at 0 0 0)
			(layer "F.Fab")
			(hide yes)
			(effects
				(font
					(size 1 1)
					(thickness 0.15)
				)
			)
		)
		(property "Public" "False"
			(at 0 0 0)
			(layer "F.Fab")
			(hide yes)
			(effects
				(font
					(size 1 1)
					(thickness 0.15)
				)
			)
		)
		(property "Val" "1u"
			(at 0 0 0)
			(layer "F.Fab")
			(hide yes)
			(effects
				(font
					(size 1 1)
					(thickness 0.15)
				)
			)
		)
		(property "Voltage" ""
			(at 0 0 0)
			(layer "F.Fab")
			(hide yes)
			(effects
				(font
					(size 1 1)
					(thickness 0.15)
				)
			)
		)
		(sheetname "Power")
		(sheetfile "power.kicad_sch")
		(attr smd)
		(fp_rect
			(start -0.925 -0.47)
			(end 0.925 0.47)
			(stroke
				(width 0.05)
				(type default)
			)
			(fill no)
			(layer "F.CrtYd")
		)
		(fp_line
			(start -0.494 -0.25)
			(end 0.504 -0.25)
			(stroke
				(width 0.15)
				(type solid)
			)
			(layer "F.Fab")
		)
		(fp_line
			(start -0.494 0.248)
			(end -0.494 -0.25)
			(stroke
				(width 0.15)
				(type solid)
			)
			(layer "F.Fab")
		)
		(fp_line
			(start 0.504 -0.25)
			(end 0.504 0.248)
			(stroke
				(width 0.15)
				(type solid)
			)
			(layer "F.Fab")
		)
		(fp_line
			(start 0.504 0.248)
			(end -0.494 0.248)
			(stroke
				(width 0.15)
				(type solid)
			)
			(layer "F.Fab")
		)
		(pad "1" smd roundrect
			(at -0.48 0)
			(size 0.59 0.64)
			(layers "F.Cu" "F.Mask" "F.Paste")
			(roundrect_rratio 0.25)
			(net 1 "GND")
			(pintype "passive")
			(teardrops
				(best_length_ratio 0.2)
				(max_length 1)
				(best_width_ratio 0.9)
				(max_width 2)
				(curved_edges yes)
				(filter_ratio 0.9)
				(enabled yes)
				(allow_two_segments yes)
				(prefer_zone_connections yes)
			)
		)
		(pad "2" smd roundrect
			(at 0.48 0)
			(size 0.59 0.64)
			(layers "F.Cu" "F.Mask" "F.Paste")
			(roundrect_rratio 0.25)
			(net 52 "+5V")
			(pintype "passive")
			(teardrops
				(best_length_ratio 0.2)
				(max_length 1)
				(best_width_ratio 0.9)
				(max_width 2)
				(curved_edges yes)
				(filter_ratio 0.9)
				(enabled yes)
				(allow_two_segments yes)
				(prefer_zone_connections yes)
			)
		)
	)
	(footprint "antmicro-footprints:C_0402_1005Metric"
		(layer "F.Cu")
		(at 248.695708 75.76)
		(descr "Capacitor SMD 0402")
		(tags "capacitor SMD 0402")
		(property "Reference" "C91"
			(at -2.975 0.45 0)
			(layer "F.SilkS")
			(effects
				(font
					(size 0.7 0.7)
					(thickness 0.15)
				)
				(justify left bottom)
			)
		)
		(property "Value" "C_100n_0402"
			(at -1.022927 2.155213 0)
			(layer "F.Fab")
			(effects
				(font
					(size 0.7 0.7)
					(thickness 0.15)
				)
				(justify left bottom)
			)
		)
		(property "Datasheet" "https://www.murata.com/products/productdetail?partno=GRM155R61H104KE14%23"
			(at 0 0 0)
			(layer "F.Fab")
			(hide yes)
			(effects
				(font
					(size 1.27 1.27)
					(thickness 0.15)
				)
			)
		)
		(property "Author" "Antmicro"
			(at 0 0 0)
			(layer "F.Fab")
			(hide yes)
			(effects
				(font
					(size 1 1)
					(thickness 0.15)
				)
			)
		)
		(property "Dielectric" "X5R"
			(at 0 0 0)
			(layer "F.Fab")
			(hide yes)
			(effects
				(font
					(size 1 1)
					(thickness 0.15)
				)
			)
		)
		(property "License" "Apache-2.0"
			(at 0 0 0)
			(layer "F.Fab")
			(hide yes)
			(effects
				(font
					(size 1 1)
					(thickness 0.15)
				)
			)
		)
		(property "MPN" "GRM155R61H104KE14D"
			(at 0 0 0)
			(layer "F.Fab")
			(hide yes)
			(effects
				(font
					(size 1 1)
					(thickness 0.15)
				)
			)
		)
		(property "Manufacturer" "Murata"
			(at 0 0 0)
			(layer "F.Fab")
			(hide yes)
			(effects
				(font
					(size 1 1)
					(thickness 0.15)
				)
			)
		)
		(property "Public" "False"
			(at 0 0 0)
			(layer "F.Fab")
			(hide yes)
			(effects
				(font
					(size 1 1)
					(thickness 0.15)
				)
			)
		)
		(property "Val" "100n"
			(at 0 0 0)
			(layer "F.Fab")
			(hide yes)
			(effects
				(font
					(size 1 1)
					(thickness 0.15)
				)
			)
		)
		(property "Voltage" "50V"
			(at 0 0 0)
			(layer "F.Fab")
			(hide yes)
			(effects
				(font
					(size 1 1)
					(thickness 0.15)
				)
			)
		)
		(sheetname "Misc")
		(sheetfile "misc.kicad_sch")
		(attr smd)
		(fp_rect
			(start -0.925 -0.47)
			(end 0.925 0.47)
			(stroke
				(width 0.05)
				(type default)
			)
			(fill no)
			(layer "F.CrtYd")
		)
		(fp_line
			(start -0.494 -0.25)
			(end 0.504 -0.25)
			(stroke
				(width 0.15)
				(type solid)
			)
			(layer "F.Fab")
		)
		(fp_line
			(start -0.494 0.248)
			(end -0.494 -0.25)
			(stroke
				(width 0.15)
				(type solid)
			)
			(layer "F.Fab")
		)
		(fp_line
			(start 0.504 -0.25)
			(end 0.504 0.248)
			(stroke
				(width 0.15)
				(type solid)
			)
			(layer "F.Fab")
		)
		(fp_line
			(start 0.504 0.248)
			(end -0.494 0.248)
			(stroke
				(width 0.15)
				(type solid)
			)
			(layer "F.Fab")
		)
		(pad "1" smd roundrect
			(at -0.48 0)
			(size 0.59 0.64)
			(layers "F.Cu" "F.Mask" "F.Paste")
			(roundrect_rratio 0.25)
			(net 1 "GND")
			(pintype "passive")
			(teardrops
				(best_length_ratio 0.2)
				(max_length 1)
				(best_width_ratio 0.9)
				(max_width 2)
				(curved_edges yes)
				(filter_ratio 0.9)
				(enabled yes)
				(allow_two_segments yes)
				(prefer_zone_connections yes)
			)
		)
		(pad "2" smd roundrect
			(at 0.48 0)
			(size 0.59 0.64)
			(layers "F.Cu" "F.Mask" "F.Paste")
			(roundrect_rratio 0.25)
			(net 52 "+5V")
			(pintype "passive")
			(teardrops
				(best_length_ratio 0.2)
				(max_length 1)
				(best_width_ratio 0.9)
				(max_width 2)
				(curved_edges yes)
				(filter_ratio 0.9)
				(enabled yes)
				(allow_two_segments yes)
				(prefer_zone_connections yes)
			)
		)
	)
)
